FILE_TYPE = CONNECTIVITY;
{Allegro Design Entry HDL 17.4-2019 S026 (4007227) 1/17/2022}
"PAGE_NUMBER" = 2;
0"NC";
END.
